FILE_TYPE = CONNECTIVITY;
{Allegro Design Entry HDL 17.2-2016 S081 (4005846) 1/11/2022}
"PAGE_NUMBER" = 164;
0"NC";
1"P5E_CPU0_PE0_TX_DP<7:0>";
2"P5E_CPU0_PE0_TX_DN<7:0>";
3"P5E_CPU0_PE0_TX_DP<15:8>";
4"P5E_CPU0_PE0_TX_DN<15:8>";
5"P5E_CPU0_PE0_TX_C_DP<15:8>";
6"P5E_CPU0_PE0_TX_C_DP<7:0>";
7"P5E_CPU0_PE0_TX_C_DN<7:0>";
8"P5E_CPU0_PE0_TX_C_DN<15:8>";
9"P5E_CPU0_PE2_TX_DN<7:0>";
10"P5E_CPU0_PE2_TX_DP<7:0>";
11"P5E_CPU0_PE2_TX_DP<15:8>";
12"P5E_CPU0_PE2_TX_DN<15:8>";
13"P5E_CPU0_PE2_TX_C_DN<7:0>";
14"P5E_CPU0_PE2_TX_C_DP<7:0>";
15"P5E_CPU0_PE2_TX_C_DN<15:8>";
16"P5E_CPU0_PE2_TX_C_DP<15:8>";
17"P5E_CPU0_PE0_TX_DP<8>";
18"P5E_CPU0_PE2_TX_DP<0>";
19"P5E_CPU0_PE2_TX_C_DP<1>";
20"P5E_CPU0_PE2_TX_C_DP<2>";
21"P5E_CPU0_PE2_TX_C_DN<2>";
22"P5E_CPU0_PE2_TX_DP<5>";
23"P5E_CPU0_PE2_TX_DN<5>";
24"P5E_CPU0_PE2_TX_DP<6>";
25"P5E_CPU0_PE2_TX_DN<6>";
26"P5E_CPU0_PE2_TX_DP<7>";
27"P5E_CPU0_PE2_TX_DN<7>";
28"P5E_CPU0_PE2_TX_C_DP<3>";
29"P5E_CPU0_PE2_TX_C_DN<1>";
30"P5E_CPU0_PE2_TX_C_DP<0>";
31"P5E_CPU0_PE2_TX_C_DP<15>";
32"P5E_CPU0_PE2_TX_C_DP<14>";
33"P5E_CPU0_PE2_TX_C_DP<13>";
34"P5E_CPU0_PE2_TX_C_DN<15>";
35"P5E_CPU0_PE2_TX_C_DN<14>";
36"P5E_CPU0_PE2_TX_C_DN<13>";
37"P5E_CPU0_PE2_TX_C_DP<12>";
38"P5E_CPU0_PE2_TX_C_DP<8>";
39"P5E_CPU0_PE2_TX_C_DP<9>";
40"P5E_CPU0_PE2_TX_C_DP<10>";
41"P5E_CPU0_PE2_TX_C_DP<11>";
42"P5E_CPU0_PE2_TX_C_DN<11>";
43"P5E_CPU0_PE2_TX_C_DN<12>";
44"P5E_CPU0_PE2_TX_C_DN<10>";
45"P5E_CPU0_PE2_TX_C_DN<8>";
46"P5E_CPU0_PE2_TX_C_DN<9>";
47"P5E_CPU0_PE2_TX_C_DP<5>";
48"P5E_CPU0_PE2_TX_C_DP<7>";
49"P5E_CPU0_PE2_TX_C_DP<6>";
50"P5E_CPU0_PE2_TX_C_DN<7>";
51"P5E_CPU0_PE2_TX_C_DN<4>";
52"P5E_CPU0_PE2_TX_C_DN<5>";
53"P5E_CPU0_PE2_TX_C_DN<6>";
54"P5E_CPU0_PE2_TX_C_DP<4>";
55"P5E_CPU0_PE2_TX_C_DN<3>";
56"P5E_CPU0_PE2_TX_C_DN<0>";
57"P5E_CPU0_PE2_TX_DP<15>";
58"P5E_CPU0_PE2_TX_DP<13>";
59"P5E_CPU0_PE2_TX_DN<15>";
60"P5E_CPU0_PE2_TX_DN<13>";
61"P5E_CPU0_PE2_TX_DN<14>";
62"P5E_CPU0_PE2_TX_DP<14>";
63"P5E_CPU0_PE2_TX_DP<10>";
64"P5E_CPU0_PE2_TX_DN<10>";
65"P5E_CPU0_PE2_TX_DN<9>";
66"P5E_CPU0_PE2_TX_DN<12>";
67"P5E_CPU0_PE2_TX_DP<12>";
68"P5E_CPU0_PE2_TX_DP<9>";
69"P5E_CPU0_PE2_TX_DN<11>";
70"P5E_CPU0_PE2_TX_DP<8>";
71"P5E_CPU0_PE2_TX_DN<8>";
72"P5E_CPU0_PE2_TX_DP<11>";
73"P5E_CPU0_PE2_TX_DN<4>";
74"P5E_CPU0_PE2_TX_DN<2>";
75"P5E_CPU0_PE2_TX_DN<1>";
76"P5E_CPU0_PE2_TX_DP<3>";
77"P5E_CPU0_PE2_TX_DN<3>";
78"P5E_CPU0_PE2_TX_DP<4>";
79"P5E_CPU0_PE2_TX_DP<1>";
80"P5E_CPU0_PE2_TX_DP<2>";
81"P5E_CPU0_PE2_TX_DN<0>";
82"P5E_CPU0_PE0_TX_C_DP<10>";
83"P5E_CPU0_PE0_TX_C_DN<10>";
84"P5E_CPU0_PE0_TX_C_DP<3>";
85"P5E_CPU0_PE0_TX_C_DP<4>";
86"P5E_CPU0_PE0_TX_C_DP<2>";
87"P5E_CPU0_PE0_TX_C_DN<3>";
88"P5E_CPU0_PE0_TX_C_DP<0>";
89"P5E_CPU0_PE0_TX_C_DN<0>";
90"P5E_CPU0_PE0_TX_C_DN<4>";
91"P5E_CPU0_PE0_TX_C_DN<1>";
92"P5E_CPU0_PE0_TX_C_DP<1>";
93"P5E_CPU0_PE0_TX_C_DN<2>";
94"P5E_CPU0_PE0_TX_C_DP<5>";
95"P5E_CPU0_PE0_TX_C_DN<5>";
96"P5E_CPU0_PE0_TX_C_DP<6>";
97"P5E_CPU0_PE0_TX_C_DN<6>";
98"P5E_CPU0_PE0_TX_C_DP<8>";
99"P5E_CPU0_PE0_TX_C_DN<14>";
100"P5E_CPU0_PE0_TX_C_DN<9>";
101"P5E_CPU0_PE0_TX_C_DP<12>";
102"P5E_CPU0_PE0_TX_C_DN<12>";
103"P5E_CPU0_PE0_TX_C_DP<13>";
104"P5E_CPU0_PE0_TX_C_DN<11>";
105"P5E_CPU0_PE0_TX_C_DN<15>";
106"P5E_CPU0_PE0_TX_C_DP<15>";
107"P5E_CPU0_PE0_TX_C_DP<14>";
108"P5E_CPU0_PE0_TX_C_DN<13>";
109"P5E_CPU0_PE0_TX_C_DP<9>";
110"P5E_CPU0_PE0_TX_C_DN<8>";
111"P5E_CPU0_PE0_TX_C_DN<7>";
112"P5E_CPU0_PE0_TX_C_DP<7>";
113"P5E_CPU0_PE0_TX_C_DP<11>";
114"P5E_CPU0_PE0_TX_DP<10>";
115"P5E_CPU0_PE0_TX_DP<13>";
116"P5E_CPU0_PE0_TX_DN<9>";
117"P5E_CPU0_PE0_TX_DN<11>";
118"P5E_CPU0_PE0_TX_DN<12>";
119"P5E_CPU0_PE0_TX_DN<13>";
120"P5E_CPU0_PE0_TX_DP<12>";
121"P5E_CPU0_PE0_TX_DN<15>";
122"P5E_CPU0_PE0_TX_DP<15>";
123"P5E_CPU0_PE0_TX_DP<9>";
124"P5E_CPU0_PE0_TX_DN<8>";
125"P5E_CPU0_PE0_TX_DN<10>";
126"P5E_CPU0_PE0_TX_DN<14>";
127"P5E_CPU0_PE0_TX_DP<14>";
128"P5E_CPU0_PE0_TX_DP<11>";
129"P5E_CPU0_PE0_TX_DN<6>";
130"P5E_CPU0_PE0_TX_DP<7>";
131"P5E_CPU0_PE0_TX_DP<2>";
132"P5E_CPU0_PE0_TX_DP<3>";
133"P5E_CPU0_PE0_TX_DP<4>";
134"P5E_CPU0_PE0_TX_DN<4>";
135"P5E_CPU0_PE0_TX_DN<0>";
136"P5E_CPU0_PE0_TX_DN<2>";
137"P5E_CPU0_PE0_TX_DN<3>";
138"P5E_CPU0_PE0_TX_DP<6>";
139"P5E_CPU0_PE0_TX_DP<5>";
140"P5E_CPU0_PE0_TX_DN<5>";
141"P5E_CPU0_PE0_TX_DN<1>";
142"P5E_CPU0_PE0_TX_DP<1>";
143"P5E_CPU0_PE0_TX_DN<7>";
144"P5E_CPU0_PE0_TX_DP<0>";
%"TAP"
"1","(-1550,925)","2","standard","I10";
;
CDS_LIB"standard"
BODY_TYPE"PLUMBING"
HDL_TAP"TRUE";
"B \NAC \NWC"1;
"S \NAC"
BN"3"132;
%"TAP"
"1","(175,2700)","0","standard","I100";
;
CDS_LIB"standard"
BODY_TYPE"PLUMBING"
HDL_TAP"TRUE";
"B \NAC \NWC"5;
"S \NAC"
BN"10"82;
%"TAP"
"1","(175,3100)","0","standard","I101";
;
CDS_LIB"standard"
BODY_TYPE"PLUMBING"
HDL_TAP"TRUE";
"B \NAC \NWC"5;
"S \NAC"
BN"12"101;
%"TAP"
"1","(175,3300)","0","standard","I102";
;
CDS_LIB"standard"
BODY_TYPE"PLUMBING"
HDL_TAP"TRUE";
"B \NAC \NWC"5;
"S \NAC"
BN"13"103;
%"TAP"
"1","(175,3500)","0","standard","I103";
;
CDS_LIB"standard"
BODY_TYPE"PLUMBING"
HDL_TAP"TRUE";
"B \NAC \NWC"5;
"S \NAC"
BN"14"107;
%"TAP"
"1","(175,3700)","0","standard","I104";
;
CDS_LIB"standard"
BODY_TYPE"PLUMBING"
HDL_TAP"TRUE";
"B \NAC \NWC"5;
"S \NAC"
BN"15"106;
%"TAP"
"1","(3000,525)","2","standard","I109";
;
CDS_LIB"standard"
BODY_TYPE"PLUMBING"
HDL_TAP"TRUE";
"B \NAC \NWC"10;
"S \NAC"
BN"1"79;
%"TAP"
"1","(-1550,1125)","2","standard","I11";
;
CDS_LIB"standard"
BODY_TYPE"PLUMBING"
HDL_TAP"TRUE";
"B \NAC \NWC"1;
"S \NAC"
BN"4"133;
%"TAP"
"1","(3000,325)","2","standard","I110";
;
CDS_LIB"standard"
BODY_TYPE"PLUMBING"
HDL_TAP"TRUE";
"B \NAC \NWC"10;
"S \NAC"
BN"0"18;
%"TAP"
"1","(3000,925)","2","standard","I111";
;
CDS_LIB"standard"
BODY_TYPE"PLUMBING"
HDL_TAP"TRUE";
"B \NAC \NWC"10;
"S \NAC"
BN"3"76;
%"TAP"
"1","(3000,725)","2","standard","I112";
;
CDS_LIB"standard"
BODY_TYPE"PLUMBING"
HDL_TAP"TRUE";
"B \NAC \NWC"10;
"S \NAC"
BN"2"80;
%"TAP"
"1","(3000,1525)","2","standard","I113";
;
CDS_LIB"standard"
BODY_TYPE"PLUMBING"
HDL_TAP"TRUE";
"B \NAC \NWC"10;
"S \NAC"
BN"6"24;
%"TAP"
"1","(3000,1325)","2","standard","I114";
;
CDS_LIB"standard"
BODY_TYPE"PLUMBING"
HDL_TAP"TRUE";
"B \NAC \NWC"10;
"S \NAC"
BN"5"22;
%"TAP"
"1","(3000,1125)","2","standard","I115";
;
CDS_LIB"standard"
BODY_TYPE"PLUMBING"
HDL_TAP"TRUE";
"B \NAC \NWC"10;
"S \NAC"
BN"4"78;
%"TAP"
"1","(3000,1725)","2","standard","I116";
;
CDS_LIB"standard"
BODY_TYPE"PLUMBING"
HDL_TAP"TRUE";
"B \NAC \NWC"10;
"S \NAC"
BN"7"26;
%"TAP"
"1","(3250,375)","2","standard","I117";
;
CDS_LIB"standard"
BODY_TYPE"PLUMBING"
HDL_TAP"TRUE";
"B \NAC \NWC"9;
"S \NAC"
BN"0"81;
%"TAP"
"1","(3250,575)","2","standard","I118";
;
CDS_LIB"standard"
BODY_TYPE"PLUMBING"
HDL_TAP"TRUE";
"B \NAC \NWC"9;
"S \NAC"
BN"1"75;
%"TAP"
"1","(3250,775)","2","standard","I119";
;
CDS_LIB"standard"
BODY_TYPE"PLUMBING"
HDL_TAP"TRUE";
"B \NAC \NWC"9;
"S \NAC"
BN"2"74;
%"TAP"
"1","(-1300,775)","2","standard","I12";
;
CDS_LIB"standard"
BODY_TYPE"PLUMBING"
HDL_TAP"TRUE";
"B \NAC \NWC"2;
"S \NAC"
BN"2"136;
%"TAP"
"1","(3250,975)","2","standard","I120";
;
CDS_LIB"standard"
BODY_TYPE"PLUMBING"
HDL_TAP"TRUE";
"B \NAC \NWC"9;
"S \NAC"
BN"3"77;
%"Q_CAP_DIFFBUS"
"2","(3975,325)","2","pure_quanta","I121";
;
PART_NUMBER"SP_CH4221MEE01"
VALUE"DIFF BUS_0.22UF"
$LOCATION"C965"
TOLERANCE"20%"
PACK_TYPE"C0201"
MATERIAL"X6S"
VOLTAGE"6.3V"
CDS_LMAN_SYM_OUTLINE"-25,50,25,-50"
CDS_LIB"pure_quanta"
PIN_NAMES_ROTATE"TRUE"
$LOCATION"C965"
CDS_LOCATION"C965"
$SEC"1"
CDS_SEC"1";
"2"
$PN"2"18;
"1"
$PN"1"30;
%"Q_CAP_DIFFBUS"
"2","(3975,375)","2","pure_quanta","I122";
;
PART_NUMBER"SP_CH4221MEE01"
VALUE"DIFF BUS_0.22UF"
$LOCATION"C964"
TOLERANCE"20%"
PACK_TYPE"C0201"
MATERIAL"X6S"
VOLTAGE"6.3V"
CDS_LMAN_SYM_OUTLINE"-25,50,25,-50"
CDS_LIB"pure_quanta"
PIN_NAMES_ROTATE"TRUE"
$LOCATION"C964"
CDS_LOCATION"C964"
$SEC"1"
CDS_SEC"1";
"2"
$PN"2"81;
"1"
$PN"1"56;
%"Q_CAP_DIFFBUS"
"2","(3975,525)","2","pure_quanta","I123";
;
PART_NUMBER"SP_CH4221MEE01"
VALUE"DIFF BUS_0.22UF"
$LOCATION"C963"
TOLERANCE"20%"
PACK_TYPE"C0201"
MATERIAL"X6S"
VOLTAGE"6.3V"
CDS_LMAN_SYM_OUTLINE"-25,50,25,-50"
CDS_LIB"pure_quanta"
PIN_NAMES_ROTATE"TRUE"
$LOCATION"C963"
CDS_LOCATION"C963"
$SEC"1"
CDS_SEC"1";
"2"
$PN"2"79;
"1"
$PN"1"19;
%"Q_CAP_DIFFBUS"
"2","(3975,575)","2","pure_quanta","I124";
;
PART_NUMBER"SP_CH4221MEE01"
VALUE"DIFF BUS_0.22UF"
$LOCATION"C962"
TOLERANCE"20%"
PACK_TYPE"C0201"
MATERIAL"X6S"
VOLTAGE"6.3V"
CDS_LIB"pure_quanta"
CDS_LMAN_SYM_OUTLINE"-25,50,25,-50"
PIN_NAMES_ROTATE"TRUE"
$LOCATION"C962"
CDS_LOCATION"C962"
$SEC"1"
CDS_SEC"1";
"2"
$PN"2"75;
"1"
$PN"1"29;
%"Q_CAP_DIFFBUS"
"2","(3975,725)","2","pure_quanta","I125";
;
PART_NUMBER"SP_CH4221MEE01"
VALUE"DIFF BUS_0.22UF"
$LOCATION"C961"
TOLERANCE"20%"
PACK_TYPE"C0201"
MATERIAL"X6S"
VOLTAGE"6.3V"
CDS_LMAN_SYM_OUTLINE"-25,50,25,-50"
CDS_LIB"pure_quanta"
PIN_NAMES_ROTATE"TRUE"
$LOCATION"C961"
CDS_LOCATION"C961"
$SEC"1"
CDS_SEC"1";
"2"
$PN"2"80;
"1"
$PN"1"20;
%"Q_CAP_DIFFBUS"
"2","(3975,775)","2","pure_quanta","I126";
;
PART_NUMBER"SP_CH4221MEE01"
VALUE"DIFF BUS_0.22UF"
$LOCATION"C960"
TOLERANCE"20%"
PACK_TYPE"C0201"
MATERIAL"X6S"
VOLTAGE"6.3V"
CDS_LMAN_SYM_OUTLINE"-25,50,25,-50"
CDS_LIB"pure_quanta"
PIN_NAMES_ROTATE"TRUE"
$LOCATION"C960"
CDS_LOCATION"C960"
$SEC"1"
CDS_SEC"1";
"2"
$PN"2"74;
"1"
$PN"1"21;
%"Q_CAP_DIFFBUS"
"2","(3975,925)","2","pure_quanta","I127";
;
PART_NUMBER"SP_CH4221MEE01"
VALUE"DIFF BUS_0.22UF"
$LOCATION"C959"
TOLERANCE"20%"
PACK_TYPE"C0201"
MATERIAL"X6S"
VOLTAGE"6.3V"
CDS_LIB"pure_quanta"
CDS_LMAN_SYM_OUTLINE"-25,50,25,-50"
PIN_NAMES_ROTATE"TRUE"
$LOCATION"C959"
CDS_LOCATION"C959"
$SEC"1"
CDS_SEC"1";
"2"
$PN"2"76;
"1"
$PN"1"28;
%"Q_CAP_DIFFBUS"
"2","(3975,975)","2","pure_quanta","I128";
;
PART_NUMBER"SP_CH4221MEE01"
VALUE"DIFF BUS_0.22UF"
$LOCATION"C958"
TOLERANCE"20%"
PACK_TYPE"C0201"
MATERIAL"X6S"
VOLTAGE"6.3V"
CDS_LIB"pure_quanta"
CDS_LMAN_SYM_OUTLINE"-25,50,25,-50"
PIN_NAMES_ROTATE"TRUE"
$LOCATION"C958"
CDS_LOCATION"C958"
$SEC"1"
CDS_SEC"1";
"2"
$PN"2"77;
"1"
$PN"1"55;
%"TAP"
"1","(3250,1375)","2","standard","I129";
;
CDS_LIB"standard"
BODY_TYPE"PLUMBING"
HDL_TAP"TRUE";
"B \NAC \NWC"9;
"S \NAC"
BN"5"23;
%"TAP"
"1","(-1300,975)","2","standard","I13";
;
CDS_LIB"standard"
BODY_TYPE"PLUMBING"
HDL_TAP"TRUE";
"B \NAC \NWC"2;
"S \NAC"
BN"3"137;
%"TAP"
"1","(3250,1175)","2","standard","I130";
;
CDS_LIB"standard"
BODY_TYPE"PLUMBING"
HDL_TAP"TRUE";
"B \NAC \NWC"9;
"S \NAC"
BN"4"73;
%"TAP"
"1","(3250,1575)","2","standard","I131";
;
CDS_LIB"standard"
BODY_TYPE"PLUMBING"
HDL_TAP"TRUE";
"B \NAC \NWC"9;
"S \NAC"
BN"6"25;
%"TAP"
"1","(3250,1775)","2","standard","I132";
;
CDS_LIB"standard"
BODY_TYPE"PLUMBING"
HDL_TAP"TRUE";
"B \NAC \NWC"9;
"S \NAC"
BN"7"27;
%"Q_CAP_DIFFBUS"
"2","(3975,1375)","2","pure_quanta","I133";
;
PART_NUMBER"SP_CH4221MEE01"
VALUE"DIFF BUS_0.22UF"
$LOCATION"C954"
TOLERANCE"20%"
PACK_TYPE"C0201"
MATERIAL"X6S"
VOLTAGE"6.3V"
CDS_LMAN_SYM_OUTLINE"-25,50,25,-50"
CDS_LIB"pure_quanta"
PIN_NAMES_ROTATE"TRUE"
$LOCATION"C954"
CDS_LOCATION"C954"
$SEC"1"
CDS_SEC"1";
"2"
$PN"2"23;
"1"
$PN"1"52;
%"Q_CAP_DIFFBUS"
"2","(3975,1525)","2","pure_quanta","I134";
;
PART_NUMBER"SP_CH4221MEE01"
VALUE"DIFF BUS_0.22UF"
$LOCATION"C953"
TOLERANCE"20%"
PACK_TYPE"C0201"
MATERIAL"X6S"
VOLTAGE"6.3V"
CDS_LMAN_SYM_OUTLINE"-25,50,25,-50"
CDS_LIB"pure_quanta"
PIN_NAMES_ROTATE"TRUE"
$LOCATION"C953"
CDS_LOCATION"C953"
$SEC"1"
CDS_SEC"1";
"2"
$PN"2"24;
"1"
$PN"1"49;
%"Q_CAP_DIFFBUS"
"2","(3975,1575)","2","pure_quanta","I135";
;
PART_NUMBER"SP_CH4221MEE01"
VALUE"DIFF BUS_0.22UF"
$LOCATION"C952"
TOLERANCE"20%"
PACK_TYPE"C0201"
MATERIAL"X6S"
VOLTAGE"6.3V"
CDS_LMAN_SYM_OUTLINE"-25,50,25,-50"
CDS_LIB"pure_quanta"
PIN_NAMES_ROTATE"TRUE"
$LOCATION"C952"
CDS_LOCATION"C952"
$SEC"1"
CDS_SEC"1";
"2"
$PN"2"25;
"1"
$PN"1"53;
%"Q_CAP_DIFFBUS"
"2","(3975,1725)","2","pure_quanta","I136";
;
PART_NUMBER"SP_CH4221MEE01"
VALUE"DIFF BUS_0.22UF"
$LOCATION"C951"
TOLERANCE"20%"
PACK_TYPE"C0201"
MATERIAL"X6S"
VOLTAGE"6.3V"
CDS_LMAN_SYM_OUTLINE"-25,50,25,-50"
CDS_LIB"pure_quanta"
PIN_NAMES_ROTATE"TRUE"
$LOCATION"C951"
CDS_LOCATION"C951"
$SEC"1"
CDS_SEC"1";
"2"
$PN"2"26;
"1"
$PN"1"48;
%"Q_CAP_DIFFBUS"
"2","(3975,1775)","2","pure_quanta","I137";
;
PART_NUMBER"SP_CH4221MEE01"
VALUE"DIFF BUS_0.22UF"
$LOCATION"C950"
TOLERANCE"20%"
PACK_TYPE"C0201"
MATERIAL"X6S"
VOLTAGE"6.3V"
CDS_LIB"pure_quanta"
CDS_LMAN_SYM_OUTLINE"-25,50,25,-50"
PIN_NAMES_ROTATE"TRUE"
$LOCATION"C950"
CDS_LOCATION"C950"
$SEC"1"
CDS_SEC"1";
"2"
$PN"2"27;
"1"
$PN"1"50;
%"TAP"
"1","(3000,2500)","2","standard","I138";
;
CDS_LIB"standard"
BODY_TYPE"PLUMBING"
HDL_TAP"TRUE";
"B \NAC \NWC"11;
"S \NAC"
BN"9"68;
%"TAP"
"1","(3000,2300)","2","standard","I139";
;
CDS_LIB"standard"
BODY_TYPE"PLUMBING"
HDL_TAP"TRUE";
"B \NAC \NWC"11;
"S \NAC"
BN"8"70;
%"TAP"
"1","(-1550,1325)","2","standard","I14";
;
CDS_LIB"standard"
BODY_TYPE"PLUMBING"
HDL_TAP"TRUE";
"B \NAC \NWC"1;
"S \NAC"
BN"5"139;
%"TAP"
"1","(3000,3100)","2","standard","I140";
;
CDS_LIB"standard"
BODY_TYPE"PLUMBING"
HDL_TAP"TRUE";
"B \NAC \NWC"11;
"S \NAC"
BN"12"67;
%"TAP"
"1","(3000,2900)","2","standard","I141";
;
CDS_LIB"standard"
BODY_TYPE"PLUMBING"
HDL_TAP"TRUE";
"B \NAC \NWC"11;
"S \NAC"
BN"11"72;
%"TAP"
"1","(3000,2700)","2","standard","I142";
;
CDS_LIB"standard"
BODY_TYPE"PLUMBING"
HDL_TAP"TRUE";
"B \NAC \NWC"11;
"S \NAC"
BN"10"63;
%"TAP"
"1","(3000,3300)","2","standard","I143";
;
CDS_LIB"standard"
BODY_TYPE"PLUMBING"
HDL_TAP"TRUE";
"B \NAC \NWC"11;
"S \NAC"
BN"13"58;
%"TAP"
"1","(3000,3500)","2","standard","I144";
;
CDS_LIB"standard"
BODY_TYPE"PLUMBING"
HDL_TAP"TRUE";
"B \NAC \NWC"11;
"S \NAC"
BN"14"62;
%"TAP"
"1","(3000,3700)","2","standard","I145";
;
CDS_LIB"standard"
BODY_TYPE"PLUMBING"
HDL_TAP"TRUE";
"B \NAC \NWC"11;
"S \NAC"
BN"15"57;
%"TAP"
"1","(3250,2350)","2","standard","I146";
;
CDS_LIB"standard"
BODY_TYPE"PLUMBING"
HDL_TAP"TRUE";
"B \NAC \NWC"12;
"S \NAC"
BN"8"71;
%"TAP"
"1","(3250,2550)","2","standard","I147";
;
CDS_LIB"standard"
BODY_TYPE"PLUMBING"
HDL_TAP"TRUE";
"B \NAC \NWC"12;
"S \NAC"
BN"9"65;
%"TAP"
"1","(3250,2750)","2","standard","I148";
;
CDS_LIB"standard"
BODY_TYPE"PLUMBING"
HDL_TAP"TRUE";
"B \NAC \NWC"12;
"S \NAC"
BN"10"64;
%"TAP"
"1","(3250,2950)","2","standard","I149";
;
CDS_LIB"standard"
BODY_TYPE"PLUMBING"
HDL_TAP"TRUE";
"B \NAC \NWC"12;
"S \NAC"
BN"11"69;
%"TAP"
"1","(-1550,1525)","2","standard","I15";
;
CDS_LIB"standard"
BODY_TYPE"PLUMBING"
HDL_TAP"TRUE";
"B \NAC \NWC"1;
"S \NAC"
BN"6"138;
%"TAP"
"1","(3250,3150)","2","standard","I150";
;
CDS_LIB"standard"
BODY_TYPE"PLUMBING"
HDL_TAP"TRUE";
"B \NAC \NWC"12;
"S \NAC"
BN"12"66;
%"Q_CAP_DIFFBUS"
"2","(3975,2300)","2","pure_quanta","I151";
;
PART_NUMBER"SP_CH4221MEE01"
VALUE"DIFF BUS_0.22UF"
$LOCATION"C949"
TOLERANCE"20%"
PACK_TYPE"C0201"
MATERIAL"X6S"
VOLTAGE"6.3V"
PIN_NAMES_ROTATE"TRUE"
CDS_LIB"pure_quanta"
CDS_LMAN_SYM_OUTLINE"-25,50,25,-50"
$LOCATION"C949"
CDS_LOCATION"C949"
$SEC"1"
CDS_SEC"1";
"2"
$PN"2"70;
"1"
$PN"1"38;
%"Q_CAP_DIFFBUS"
"2","(3975,2350)","2","pure_quanta","I152";
;
PART_NUMBER"SP_CH4221MEE01"
VALUE"DIFF BUS_0.22UF"
$LOCATION"C948"
TOLERANCE"20%"
PACK_TYPE"C0201"
MATERIAL"X6S"
VOLTAGE"6.3V"
PIN_NAMES_ROTATE"TRUE"
CDS_LIB"pure_quanta"
CDS_LMAN_SYM_OUTLINE"-25,50,25,-50"
$LOCATION"C948"
CDS_LOCATION"C948"
$SEC"1"
CDS_SEC"1";
"2"
$PN"2"71;
"1"
$PN"1"45;
%"Q_CAP_DIFFBUS"
"2","(3975,2500)","2","pure_quanta","I153";
;
PART_NUMBER"SP_CH4221MEE01"
VALUE"DIFF BUS_0.22UF"
$LOCATION"C947"
TOLERANCE"20%"
PACK_TYPE"C0201"
MATERIAL"X6S"
VOLTAGE"6.3V"
PIN_NAMES_ROTATE"TRUE"
CDS_LIB"pure_quanta"
CDS_LMAN_SYM_OUTLINE"-25,50,25,-50"
$LOCATION"C947"
CDS_LOCATION"C947"
$SEC"1"
CDS_SEC"1";
"2"
$PN"2"68;
"1"
$PN"1"39;
%"Q_CAP_DIFFBUS"
"2","(3975,2550)","2","pure_quanta","I154";
;
PART_NUMBER"SP_CH4221MEE01"
VALUE"DIFF BUS_0.22UF"
$LOCATION"C946"
TOLERANCE"20%"
PACK_TYPE"C0201"
MATERIAL"X6S"
VOLTAGE"6.3V"
PIN_NAMES_ROTATE"TRUE"
CDS_LMAN_SYM_OUTLINE"-25,50,25,-50"
CDS_LIB"pure_quanta"
$LOCATION"C946"
CDS_LOCATION"C946"
$SEC"1"
CDS_SEC"1";
"2"
$PN"2"65;
"1"
$PN"1"46;
%"Q_CAP_DIFFBUS"
"2","(3975,2700)","2","pure_quanta","I155";
;
PART_NUMBER"SP_CH4221MEE01"
VALUE"DIFF BUS_0.22UF"
$LOCATION"C945"
TOLERANCE"20%"
PACK_TYPE"C0201"
MATERIAL"X6S"
VOLTAGE"6.3V"
PIN_NAMES_ROTATE"TRUE"
CDS_LIB"pure_quanta"
CDS_LMAN_SYM_OUTLINE"-25,50,25,-50"
$LOCATION"C945"
CDS_LOCATION"C945"
$SEC"1"
CDS_SEC"1";
"2"
$PN"2"63;
"1"
$PN"1"40;
%"Q_CAP_DIFFBUS"
"2","(3975,2750)","2","pure_quanta","I156";
;
PART_NUMBER"SP_CH4221MEE01"
VALUE"DIFF BUS_0.22UF"
$LOCATION"C944"
TOLERANCE"20%"
PACK_TYPE"C0201"
MATERIAL"X6S"
VOLTAGE"6.3V"
PIN_NAMES_ROTATE"TRUE"
CDS_LIB"pure_quanta"
CDS_LMAN_SYM_OUTLINE"-25,50,25,-50"
$LOCATION"C944"
CDS_LOCATION"C944"
$SEC"1"
CDS_SEC"1";
"2"
$PN"2"64;
"1"
$PN"1"44;
%"Q_CAP_DIFFBUS"
"2","(3975,2900)","2","pure_quanta","I157";
;
PART_NUMBER"SP_CH4221MEE01"
VALUE"DIFF BUS_0.22UF"
$LOCATION"C943"
TOLERANCE"20%"
PACK_TYPE"C0201"
MATERIAL"X6S"
VOLTAGE"6.3V"
PIN_NAMES_ROTATE"TRUE"
CDS_LMAN_SYM_OUTLINE"-25,50,25,-50"
CDS_LIB"pure_quanta"
$LOCATION"C943"
CDS_LOCATION"C943"
$SEC"1"
CDS_SEC"1";
"2"
$PN"2"72;
"1"
$PN"1"41;
%"Q_CAP_DIFFBUS"
"2","(3975,2950)","2","pure_quanta","I158";
;
PART_NUMBER"SP_CH4221MEE01"
VALUE"DIFF BUS_0.22UF"
$LOCATION"C942"
TOLERANCE"20%"
PACK_TYPE"C0201"
MATERIAL"X6S"
VOLTAGE"6.3V"
PIN_NAMES_ROTATE"TRUE"
CDS_LMAN_SYM_OUTLINE"-25,50,25,-50"
CDS_LIB"pure_quanta"
$LOCATION"C942"
CDS_LOCATION"C942"
$SEC"1"
CDS_SEC"1";
"2"
$PN"2"69;
"1"
$PN"1"42;
%"Q_CAP_DIFFBUS"
"2","(3975,3100)","2","pure_quanta","I159";
;
PART_NUMBER"SP_CH4221MEE01"
VALUE"DIFF BUS_0.22UF"
$LOCATION"C941"
TOLERANCE"20%"
PACK_TYPE"C0201"
MATERIAL"X6S"
VOLTAGE"6.3V"
PIN_NAMES_ROTATE"TRUE"
CDS_LIB"pure_quanta"
CDS_LMAN_SYM_OUTLINE"-25,50,25,-50"
$LOCATION"C941"
CDS_LOCATION"C941"
$SEC"1"
CDS_SEC"1";
"2"
$PN"2"67;
"1"
$PN"1"37;
%"TAP"
"1","(-1300,1175)","2","standard","I16";
;
CDS_LIB"standard"
BODY_TYPE"PLUMBING"
HDL_TAP"TRUE";
"B \NAC \NWC"2;
"S \NAC"
BN"4"134;
%"Q_CAP_DIFFBUS"
"2","(3975,3150)","2","pure_quanta","I160";
;
PART_NUMBER"SP_CH4221MEE01"
VALUE"DIFF BUS_0.22UF"
$LOCATION"C940"
TOLERANCE"20%"
PACK_TYPE"C0201"
MATERIAL"X6S"
VOLTAGE"6.3V"
PIN_NAMES_ROTATE"TRUE"
CDS_LIB"pure_quanta"
CDS_LMAN_SYM_OUTLINE"-25,50,25,-50"
$LOCATION"C940"
CDS_LOCATION"C940"
$SEC"1"
CDS_SEC"1";
"2"
$PN"2"66;
"1"
$PN"1"43;
%"TAP"
"1","(3250,3350)","2","standard","I161";
;
CDS_LIB"standard"
BODY_TYPE"PLUMBING"
HDL_TAP"TRUE";
"B \NAC \NWC"12;
"S \NAC"
BN"13"60;
%"TAP"
"1","(3250,3550)","2","standard","I162";
;
CDS_LIB"standard"
BODY_TYPE"PLUMBING"
HDL_TAP"TRUE";
"B \NAC \NWC"12;
"S \NAC"
BN"14"61;
%"TAP"
"1","(3250,3750)","2","standard","I163";
;
CDS_LIB"standard"
BODY_TYPE"PLUMBING"
HDL_TAP"TRUE";
"B \NAC \NWC"12;
"S \NAC"
BN"15"59;
%"Q_CAP_DIFFBUS"
"2","(3975,3300)","2","pure_quanta","I164";
;
PART_NUMBER"SP_CH4221MEE01"
VALUE"DIFF BUS_0.22UF"
$LOCATION"C939"
TOLERANCE"20%"
PACK_TYPE"C0201"
MATERIAL"X6S"
VOLTAGE"6.3V"
PIN_NAMES_ROTATE"TRUE"
CDS_LIB"pure_quanta"
CDS_LMAN_SYM_OUTLINE"-25,50,25,-50"
$LOCATION"C939"
CDS_LOCATION"C939"
$SEC"1"
CDS_SEC"1";
"2"
$PN"2"58;
"1"
$PN"1"33;
%"Q_CAP_DIFFBUS"
"2","(3975,3350)","2","pure_quanta","I165";
;
PART_NUMBER"SP_CH4221MEE01"
VALUE"DIFF BUS_0.22UF"
$LOCATION"C938"
TOLERANCE"20%"
PACK_TYPE"C0201"
MATERIAL"X6S"
VOLTAGE"6.3V"
PIN_NAMES_ROTATE"TRUE"
CDS_LIB"pure_quanta"
CDS_LMAN_SYM_OUTLINE"-25,50,25,-50"
$LOCATION"C938"
CDS_LOCATION"C938"
$SEC"1"
CDS_SEC"1";
"2"
$PN"2"60;
"1"
$PN"1"36;
%"Q_CAP_DIFFBUS"
"2","(3975,3500)","2","pure_quanta","I166";
;
PART_NUMBER"SP_CH4221MEE01"
VALUE"DIFF BUS_0.22UF"
$LOCATION"C937"
TOLERANCE"20%"
PACK_TYPE"C0201"
MATERIAL"X6S"
VOLTAGE"6.3V"
PIN_NAMES_ROTATE"TRUE"
CDS_LIB"pure_quanta"
CDS_LMAN_SYM_OUTLINE"-25,50,25,-50"
$LOCATION"C937"
CDS_LOCATION"C937"
$SEC"1"
CDS_SEC"1";
"2"
$PN"2"62;
"1"
$PN"1"32;
%"Q_CAP_DIFFBUS"
"2","(3975,3550)","2","pure_quanta","I167";
;
PART_NUMBER"SP_CH4221MEE01"
VALUE"DIFF BUS_0.22UF"
$LOCATION"C936"
TOLERANCE"20%"
PACK_TYPE"C0201"
MATERIAL"X6S"
VOLTAGE"6.3V"
PIN_NAMES_ROTATE"TRUE"
CDS_LIB"pure_quanta"
CDS_LMAN_SYM_OUTLINE"-25,50,25,-50"
$LOCATION"C936"
CDS_LOCATION"C936"
$SEC"1"
CDS_SEC"1";
"2"
$PN"2"61;
"1"
$PN"1"35;
%"Q_CAP_DIFFBUS"
"2","(3975,3700)","2","pure_quanta","I168";
;
PART_NUMBER"SP_CH4221MEE01"
VALUE"DIFF BUS_0.22UF"
$LOCATION"C935"
TOLERANCE"20%"
PACK_TYPE"C0201"
MATERIAL"X6S"
VOLTAGE"6.3V"
PIN_NAMES_ROTATE"TRUE"
CDS_LIB"pure_quanta"
CDS_LMAN_SYM_OUTLINE"-25,50,25,-50"
$LOCATION"C935"
CDS_LOCATION"C935"
$SEC"1"
CDS_SEC"1";
"2"
$PN"2"57;
"1"
$PN"1"31;
%"Q_CAP_DIFFBUS"
"2","(3975,3750)","2","pure_quanta","I169";
;
PART_NUMBER"SP_CH4221MEE01"
PACK_TYPE"C0201"
TOLERANCE"20%"
VOLTAGE"6.3V"
VALUE"DIFF BUS_0.22UF"
MATERIAL"X6S"
$LOCATION"C934"
PIN_NAMES_ROTATE"TRUE"
CDS_LMAN_SYM_OUTLINE"-25,50,25,-50"
CDS_LIB"pure_quanta"
$LOCATION"C934"
CDS_LOCATION"C934"
$SEC"1"
CDS_SEC"1";
"2"
$PN"2"59;
"1"
$PN"1"34;
%"TAP"
"1","(-1300,1375)","2","standard","I17";
;
CDS_LIB"standard"
BODY_TYPE"PLUMBING"
HDL_TAP"TRUE";
"B \NAC \NWC"2;
"S \NAC"
BN"5"140;
%"TAP"
"1","(4525,575)","0","standard","I170";
;
CDS_LIB"standard"
BODY_TYPE"PLUMBING"
HDL_TAP"TRUE";
"B \NAC \NWC"13;
"S \NAC"
BN"1"29;
%"TAP"
"1","(4525,775)","0","standard","I171";
;
CDS_LIB"standard"
BODY_TYPE"PLUMBING"
HDL_TAP"TRUE";
"B \NAC \NWC"13;
"S \NAC"
BN"2"21;
%"TAP"
"1","(4525,975)","0","standard","I172";
;
CDS_LIB"standard"
BODY_TYPE"PLUMBING"
HDL_TAP"TRUE";
"B \NAC \NWC"13;
"S \NAC"
BN"3"55;
%"TAP"
"1","(4725,325)","0","standard","I173";
;
CDS_LIB"standard"
BODY_TYPE"PLUMBING"
HDL_TAP"TRUE";
"B \NAC \NWC"14;
"S \NAC"
BN"0"30;
%"TAP"
"1","(4725,525)","0","standard","I174";
;
CDS_LIB"standard"
BODY_TYPE"PLUMBING"
HDL_TAP"TRUE";
"B \NAC \NWC"14;
"S \NAC"
BN"1"19;
%"TAP"
"1","(4725,725)","0","standard","I175";
;
CDS_LIB"standard"
BODY_TYPE"PLUMBING"
HDL_TAP"TRUE";
"B \NAC \NWC"14;
"S \NAC"
BN"2"20;
%"TAP"
"1","(4725,925)","0","standard","I176";
;
CDS_LIB"standard"
BODY_TYPE"PLUMBING"
HDL_TAP"TRUE";
"B \NAC \NWC"14;
"S \NAC"
BN"3"28;
%"TAP"
"1","(4725,1125)","0","standard","I177";
;
CDS_LIB"standard"
BODY_TYPE"PLUMBING"
HDL_TAP"TRUE";
"B \NAC \NWC"14;
"S \NAC"
BN"4"54;
%"TAP"
"1","(4525,1375)","0","standard","I178";
;
CDS_LIB"standard"
BODY_TYPE"PLUMBING"
HDL_TAP"TRUE";
"B \NAC \NWC"13;
"S \NAC"
BN"5"52;
%"TAP"
"1","(4525,1175)","0","standard","I179";
;
CDS_LIB"standard"
BODY_TYPE"PLUMBING"
HDL_TAP"TRUE";
"B \NAC \NWC"13;
"S \NAC"
BN"4"51;
%"TAP"
"1","(-1300,1575)","2","standard","I18";
;
CDS_LIB"standard"
BODY_TYPE"PLUMBING"
HDL_TAP"TRUE";
"B \NAC \NWC"2;
"S \NAC"
BN"6"129;
%"TAP"
"1","(4525,1575)","0","standard","I180";
;
CDS_LIB"standard"
BODY_TYPE"PLUMBING"
HDL_TAP"TRUE";
"B \NAC \NWC"13;
"S \NAC"
BN"6"53;
%"TAP"
"1","(4525,1775)","0","standard","I181";
;
CDS_LIB"standard"
BODY_TYPE"PLUMBING"
HDL_TAP"TRUE";
"B \NAC \NWC"13;
"S \NAC"
BN"7"50;
%"TAP"
"1","(4725,1325)","0","standard","I182";
;
CDS_LIB"standard"
BODY_TYPE"PLUMBING"
HDL_TAP"TRUE";
"B \NAC \NWC"14;
"S \NAC"
BN"5"47;
%"TAP"
"1","(4725,1525)","0","standard","I183";
;
CDS_LIB"standard"
BODY_TYPE"PLUMBING"
HDL_TAP"TRUE";
"B \NAC \NWC"14;
"S \NAC"
BN"6"49;
%"TAP"
"1","(4725,1725)","0","standard","I184";
;
CDS_LIB"standard"
BODY_TYPE"PLUMBING"
HDL_TAP"TRUE";
"B \NAC \NWC"14;
"S \NAC"
BN"7"48;
%"TAP"
"1","(4525,2350)","0","standard","I187";
;
CDS_LIB"standard"
BODY_TYPE"PLUMBING"
HDL_TAP"TRUE";
"B \NAC \NWC"15;
"S \NAC"
BN"8"45;
%"TAP"
"1","(4525,2550)","0","standard","I188";
;
CDS_LIB"standard"
BODY_TYPE"PLUMBING"
HDL_TAP"TRUE";
"B \NAC \NWC"15;
"S \NAC"
BN"9"46;
%"TAP"
"1","(4525,2750)","0","standard","I189";
;
CDS_LIB"standard"
BODY_TYPE"PLUMBING"
HDL_TAP"TRUE";
"B \NAC \NWC"15;
"S \NAC"
BN"10"44;
%"TAP"
"1","(-1550,1725)","2","standard","I19";
;
CDS_LIB"standard"
BODY_TYPE"PLUMBING"
HDL_TAP"TRUE";
"B \NAC \NWC"1;
"S \NAC"
BN"7"130;
%"TAP"
"1","(4525,2950)","0","standard","I190";
;
CDS_LIB"standard"
BODY_TYPE"PLUMBING"
HDL_TAP"TRUE";
"B \NAC \NWC"15;
"S \NAC"
BN"11"42;
%"TAP"
"1","(4525,3150)","0","standard","I191";
;
CDS_LIB"standard"
BODY_TYPE"PLUMBING"
HDL_TAP"TRUE";
"B \NAC \NWC"15;
"S \NAC"
BN"12"43;
%"TAP"
"1","(4725,2300)","0","standard","I192";
;
CDS_LIB"standard"
BODY_TYPE"PLUMBING"
HDL_TAP"TRUE";
"B \NAC \NWC"16;
"S \NAC"
BN"8"38;
%"TAP"
"1","(4725,2500)","0","standard","I193";
;
CDS_LIB"standard"
BODY_TYPE"PLUMBING"
HDL_TAP"TRUE";
"B \NAC \NWC"16;
"S \NAC"
BN"9"39;
%"TAP"
"1","(4725,2700)","0","standard","I194";
;
CDS_LIB"standard"
BODY_TYPE"PLUMBING"
HDL_TAP"TRUE";
"B \NAC \NWC"16;
"S \NAC"
BN"10"40;
%"TAP"
"1","(4725,2900)","0","standard","I195";
;
CDS_LIB"standard"
BODY_TYPE"PLUMBING"
HDL_TAP"TRUE";
"B \NAC \NWC"16;
"S \NAC"
BN"11"41;
%"TAP"
"1","(4725,3100)","0","standard","I196";
;
CDS_LIB"standard"
BODY_TYPE"PLUMBING"
HDL_TAP"TRUE";
"B \NAC \NWC"16;
"S \NAC"
BN"12"37;
%"TAP"
"1","(4525,3350)","0","standard","I197";
;
CDS_LIB"standard"
BODY_TYPE"PLUMBING"
HDL_TAP"TRUE";
"B \NAC \NWC"15;
"S \NAC"
BN"13"36;
%"TAP"
"1","(4525,3550)","0","standard","I198";
;
CDS_LIB"standard"
BODY_TYPE"PLUMBING"
HDL_TAP"TRUE";
"B \NAC \NWC"15;
"S \NAC"
BN"14"35;
%"TAP"
"1","(4525,3750)","0","standard","I199";
;
CDS_LIB"standard"
BODY_TYPE"PLUMBING"
HDL_TAP"TRUE";
"B \NAC \NWC"15;
"S \NAC"
BN"15"34;
%"TAP"
"1","(-1300,1775)","2","standard","I20";
;
CDS_LIB"standard"
BODY_TYPE"PLUMBING"
HDL_TAP"TRUE";
"B \NAC \NWC"2;
"S \NAC"
BN"7"143;
%"TAP"
"1","(4725,3300)","0","standard","I200";
;
CDS_LIB"standard"
BODY_TYPE"PLUMBING"
HDL_TAP"TRUE";
"B \NAC \NWC"16;
"S \NAC"
BN"13"33;
%"TAP"
"1","(4725,3500)","0","standard","I201";
;
CDS_LIB"standard"
BODY_TYPE"PLUMBING"
HDL_TAP"TRUE";
"B \NAC \NWC"16;
"S \NAC"
BN"14"32;
%"TAP"
"1","(4725,3700)","0","standard","I202";
;
CDS_LIB"standard"
BODY_TYPE"PLUMBING"
HDL_TAP"TRUE";
"B \NAC \NWC"16;
"S \NAC"
BN"15"31;
%"TAP"
"1","(4525,375)","0","standard","I205";
;
CDS_LIB"standard"
BODY_TYPE"PLUMBING"
HDL_TAP"TRUE";
"B \NAC \NWC"13;
"S \NAC"
BN"0"56;
%"Q_CAP_DIFFBUS"
"2","(3975,1125)","2","pure_quanta","I206";
;
PART_NUMBER"SP_CH4221MEE01"
VALUE"DIFF BUS_0.22UF"
$LOCATION"C957"
TOLERANCE"20%"
PACK_TYPE"C0201"
MATERIAL"X6S"
VOLTAGE"6.3V"
CDS_LMAN_SYM_OUTLINE"-25,50,25,-50"
CDS_LIB"pure_quanta"
PIN_NAMES_ROTATE"TRUE"
$LOCATION"C957"
CDS_LOCATION"C957"
$SEC"1"
CDS_SEC"1";
"2"
$PN"2"78;
"1"
$PN"1"54;
%"Q_CAP_DIFFBUS"
"2","(3975,1175)","2","pure_quanta","I207";
;
PART_NUMBER"SP_CH4221MEE01"
VALUE"DIFF BUS_0.22UF"
$LOCATION"C956"
TOLERANCE"20%"
PACK_TYPE"C0201"
MATERIAL"X6S"
VOLTAGE"6.3V"
CDS_LMAN_SYM_OUTLINE"-25,50,25,-50"
CDS_LIB"pure_quanta"
PIN_NAMES_ROTATE"TRUE"
$LOCATION"C956"
CDS_LOCATION"C956"
$SEC"1"
CDS_SEC"1";
"2"
$PN"2"73;
"1"
$PN"1"51;
%"Q_CAP_DIFFBUS"
"2","(3975,1325)","2","pure_quanta","I208";
;
PART_NUMBER"SP_CH4221MEE01"
VALUE"DIFF BUS_0.22UF"
$LOCATION"C955"
TOLERANCE"20%"
PACK_TYPE"C0201"
MATERIAL"X6S"
VOLTAGE"6.3V"
CDS_LMAN_SYM_OUTLINE"-25,50,25,-50"
CDS_LIB"pure_quanta"
PIN_NAMES_ROTATE"TRUE"
$LOCATION"C955"
CDS_LOCATION"C955"
$SEC"1"
CDS_SEC"1";
"2"
$PN"2"22;
"1"
$PN"1"47;
%"Q_CAP_DIFFBUS"
"2","(-575,375)","2","pure_quanta","I21";
;
PART_NUMBER"SP_CH4221MEE01"
VALUE"DIFF BUS_0.22UF"
$LOCATION"C932"
TOLERANCE"20%"
PACK_TYPE"C0201"
MATERIAL"X6S"
VOLTAGE"6.3V"
CDS_LMAN_SYM_OUTLINE"-25,50,25,-50"
CDS_LIB"pure_quanta"
PIN_NAMES_ROTATE"TRUE"
$LOCATION"C932"
CDS_LOCATION"C932"
$SEC"1"
CDS_SEC"1";
"2"
$PN"2"135;
"1"
$PN"1"89;
%"Q_CAP_DIFFBUS"
"2","(-575,325)","2","pure_quanta","I22";
;
PART_NUMBER"SP_CH4221MEE01"
VALUE"DIFF BUS_0.22UF"
$LOCATION"C933"
TOLERANCE"20%"
PACK_TYPE"C0201"
MATERIAL"X6S"
VOLTAGE"6.3V"
CDS_LMAN_SYM_OUTLINE"-25,50,25,-50"
CDS_LIB"pure_quanta"
PIN_NAMES_ROTATE"TRUE"
$LOCATION"C933"
CDS_LOCATION"C933"
$SEC"1"
CDS_SEC"1";
"2"
$PN"2"144;
"1"
$PN"1"88;
%"Q_CAP_DIFFBUS"
"2","(-575,525)","2","pure_quanta","I23";
;
PART_NUMBER"SP_CH4221MEE01"
VALUE"DIFF BUS_0.22UF"
$LOCATION"C931"
TOLERANCE"20%"
PACK_TYPE"C0201"
MATERIAL"X6S"
VOLTAGE"6.3V"
CDS_LMAN_SYM_OUTLINE"-25,50,25,-50"
CDS_LIB"pure_quanta"
PIN_NAMES_ROTATE"TRUE"
$LOCATION"C931"
CDS_LOCATION"C931"
$SEC"1"
CDS_SEC"1";
"2"
$PN"2"142;
"1"
$PN"1"92;
%"Q_CAP_DIFFBUS"
"2","(-575,575)","2","pure_quanta","I24";
;
PART_NUMBER"SP_CH4221MEE01"
VALUE"DIFF BUS_0.22UF"
$LOCATION"C930"
TOLERANCE"20%"
PACK_TYPE"C0201"
MATERIAL"X6S"
VOLTAGE"6.3V"
CDS_LIB"pure_quanta"
CDS_LMAN_SYM_OUTLINE"-25,50,25,-50"
PIN_NAMES_ROTATE"TRUE"
$LOCATION"C930"
CDS_LOCATION"C930"
$SEC"1"
CDS_SEC"1";
"2"
$PN"2"141;
"1"
$PN"1"91;
%"Q_CAP_DIFFBUS"
"2","(-575,775)","2","pure_quanta","I25";
;
PART_NUMBER"SP_CH4221MEE01"
VALUE"DIFF BUS_0.22UF"
$LOCATION"C928"
TOLERANCE"20%"
PACK_TYPE"C0201"
MATERIAL"X6S"
VOLTAGE"6.3V"
CDS_LMAN_SYM_OUTLINE"-25,50,25,-50"
CDS_LIB"pure_quanta"
PIN_NAMES_ROTATE"TRUE"
$LOCATION"C928"
CDS_LOCATION"C928"
$SEC"1"
CDS_SEC"1";
"2"
$PN"2"136;
"1"
$PN"1"93;
%"Q_CAP_DIFFBUS"
"2","(-575,725)","2","pure_quanta","I26";
;
PART_NUMBER"SP_CH4221MEE01"
VALUE"DIFF BUS_0.22UF"
$LOCATION"C929"
TOLERANCE"20%"
PACK_TYPE"C0201"
MATERIAL"X6S"
VOLTAGE"6.3V"
CDS_LMAN_SYM_OUTLINE"-25,50,25,-50"
CDS_LIB"pure_quanta"
PIN_NAMES_ROTATE"TRUE"
$LOCATION"C929"
CDS_LOCATION"C929"
$SEC"1"
CDS_SEC"1";
"2"
$PN"2"131;
"1"
$PN"1"86;
%"Q_CAP_DIFFBUS"
"2","(-575,925)","2","pure_quanta","I27";
;
PART_NUMBER"SP_CH4221MEE01"
VALUE"DIFF BUS_0.22UF"
$LOCATION"C927"
TOLERANCE"20%"
PACK_TYPE"C0201"
MATERIAL"X6S"
VOLTAGE"6.3V"
CDS_LIB"pure_quanta"
CDS_LMAN_SYM_OUTLINE"-25,50,25,-50"
PIN_NAMES_ROTATE"TRUE"
$LOCATION"C927"
CDS_LOCATION"C927"
$SEC"1"
CDS_SEC"1";
"2"
$PN"2"132;
"1"
$PN"1"84;
%"Q_CAP_DIFFBUS"
"2","(-575,975)","2","pure_quanta","I28";
;
PART_NUMBER"SP_CH4221MEE01"
VALUE"DIFF BUS_0.22UF"
$LOCATION"C926"
TOLERANCE"20%"
PACK_TYPE"C0201"
MATERIAL"X6S"
VOLTAGE"6.3V"
CDS_LIB"pure_quanta"
CDS_LMAN_SYM_OUTLINE"-25,50,25,-50"
PIN_NAMES_ROTATE"TRUE"
$LOCATION"C926"
CDS_LOCATION"C926"
$SEC"1"
CDS_SEC"1";
"2"
$PN"2"137;
"1"
$PN"1"87;
%"Q_CAP_DIFFBUS"
"2","(-575,1125)","2","pure_quanta","I29";
;
PART_NUMBER"SP_CH4221MEE01"
VALUE"DIFF BUS_0.22UF"
$LOCATION"C925"
TOLERANCE"20%"
PACK_TYPE"C0201"
MATERIAL"X6S"
VOLTAGE"6.3V"
CDS_LMAN_SYM_OUTLINE"-25,50,25,-50"
CDS_LIB"pure_quanta"
PIN_NAMES_ROTATE"TRUE"
$LOCATION"C925"
CDS_LOCATION"C925"
$SEC"1"
CDS_SEC"1";
"2"
$PN"2"133;
"1"
$PN"1"85;
%"Q_CAP_DIFFBUS"
"2","(-575,1175)","2","pure_quanta","I30";
;
PART_NUMBER"SP_CH4221MEE01"
VALUE"DIFF BUS_0.22UF"
$LOCATION"C924"
TOLERANCE"20%"
PACK_TYPE"C0201"
MATERIAL"X6S"
VOLTAGE"6.3V"
CDS_LMAN_SYM_OUTLINE"-25,50,25,-50"
CDS_LIB"pure_quanta"
PIN_NAMES_ROTATE"TRUE"
$LOCATION"C924"
CDS_LOCATION"C924"
$SEC"1"
CDS_SEC"1";
"2"
$PN"2"134;
"1"
$PN"1"90;
%"Q_CAP_DIFFBUS"
"2","(-575,1325)","2","pure_quanta","I31";
;
PART_NUMBER"SP_CH4221MEE01"
VALUE"DIFF BUS_0.22UF"
$LOCATION"C923"
TOLERANCE"20%"
PACK_TYPE"C0201"
MATERIAL"X6S"
VOLTAGE"6.3V"
CDS_LMAN_SYM_OUTLINE"-25,50,25,-50"
CDS_LIB"pure_quanta"
PIN_NAMES_ROTATE"TRUE"
$LOCATION"C923"
CDS_LOCATION"C923"
$SEC"1"
CDS_SEC"1";
"2"
$PN"2"139;
"1"
$PN"1"94;
%"Q_CAP_DIFFBUS"
"2","(-575,1375)","2","pure_quanta","I32";
;
PART_NUMBER"SP_CH4221MEE01"
VALUE"DIFF BUS_0.22UF"
$LOCATION"C922"
TOLERANCE"20%"
PACK_TYPE"C0201"
MATERIAL"X6S"
VOLTAGE"6.3V"
CDS_LMAN_SYM_OUTLINE"-25,50,25,-50"
CDS_LIB"pure_quanta"
PIN_NAMES_ROTATE"TRUE"
$LOCATION"C922"
CDS_LOCATION"C922"
$SEC"1"
CDS_SEC"1";
"2"
$PN"2"140;
"1"
$PN"1"95;
%"Q_CAP_DIFFBUS"
"2","(-575,1525)","2","pure_quanta","I33";
;
PART_NUMBER"SP_CH4221MEE01"
VALUE"DIFF BUS_0.22UF"
$LOCATION"C921"
TOLERANCE"20%"
PACK_TYPE"C0201"
MATERIAL"X6S"
VOLTAGE"6.3V"
CDS_LMAN_SYM_OUTLINE"-25,50,25,-50"
CDS_LIB"pure_quanta"
PIN_NAMES_ROTATE"TRUE"
$LOCATION"C921"
CDS_LOCATION"C921"
$SEC"1"
CDS_SEC"1";
"2"
$PN"2"138;
"1"
$PN"1"96;
%"Q_CAP_DIFFBUS"
"2","(-575,1575)","2","pure_quanta","I34";
;
PART_NUMBER"SP_CH4221MEE01"
VALUE"DIFF BUS_0.22UF"
$LOCATION"C920"
TOLERANCE"20%"
PACK_TYPE"C0201"
MATERIAL"X6S"
VOLTAGE"6.3V"
CDS_LMAN_SYM_OUTLINE"-25,50,25,-50"
CDS_LIB"pure_quanta"
PIN_NAMES_ROTATE"TRUE"
$LOCATION"C920"
CDS_LOCATION"C920"
$SEC"1"
CDS_SEC"1";
"2"
$PN"2"129;
"1"
$PN"1"97;
%"Q_CAP_DIFFBUS"
"2","(-575,1775)","2","pure_quanta","I35";
;
PART_NUMBER"SP_CH4221MEE01"
VALUE"DIFF BUS_0.22UF"
$LOCATION"C918"
TOLERANCE"20%"
PACK_TYPE"C0201"
MATERIAL"X6S"
VOLTAGE"6.3V"
CDS_LIB"pure_quanta"
CDS_LMAN_SYM_OUTLINE"-25,50,25,-50"
PIN_NAMES_ROTATE"TRUE"
$LOCATION"C918"
CDS_LOCATION"C918"
$SEC"1"
CDS_SEC"1";
"2"
$PN"2"143;
"1"
$PN"1"111;
%"Q_CAP_DIFFBUS"
"2","(-575,1725)","2","pure_quanta","I36";
;
PART_NUMBER"SP_CH4221MEE01"
VALUE"DIFF BUS_0.22UF"
$LOCATION"C919"
TOLERANCE"20%"
PACK_TYPE"C0201"
MATERIAL"X6S"
VOLTAGE"6.3V"
CDS_LMAN_SYM_OUTLINE"-25,50,25,-50"
CDS_LIB"pure_quanta"
PIN_NAMES_ROTATE"TRUE"
$LOCATION"C919"
CDS_LOCATION"C919"
$SEC"1"
CDS_SEC"1";
"2"
$PN"2"130;
"1"
$PN"1"112;
%"TAP"
"1","(-1550,2300)","2","standard","I37";
;
CDS_LIB"standard"
BODY_TYPE"PLUMBING"
HDL_TAP"TRUE";
"B \NAC \NWC"3;
"S \NAC"
BN"8"17;
%"TAP"
"1","(-1550,2500)","2","standard","I38";
;
CDS_LIB"standard"
BODY_TYPE"PLUMBING"
HDL_TAP"TRUE";
"B \NAC \NWC"3;
"S \NAC"
BN"9"123;
%"TAP"
"1","(-1300,2350)","2","standard","I39";
;
CDS_LIB"standard"
BODY_TYPE"PLUMBING"
HDL_TAP"TRUE";
"B \NAC \NWC"4;
"S \NAC"
BN"8"124;
%"TAP"
"1","(-1300,2550)","2","standard","I40";
;
CDS_LIB"standard"
BODY_TYPE"PLUMBING"
HDL_TAP"TRUE";
"B \NAC \NWC"4;
"S \NAC"
BN"9"116;
%"TAP"
"1","(-1550,2700)","2","standard","I41";
;
CDS_LIB"standard"
BODY_TYPE"PLUMBING"
HDL_TAP"TRUE";
"B \NAC \NWC"3;
"S \NAC"
BN"10"114;
%"TAP"
"1","(-1550,2900)","2","standard","I42";
;
CDS_LIB"standard"
BODY_TYPE"PLUMBING"
HDL_TAP"TRUE";
"B \NAC \NWC"3;
"S \NAC"
BN"11"128;
%"TAP"
"1","(-1550,3100)","2","standard","I43";
;
CDS_LIB"standard"
BODY_TYPE"PLUMBING"
HDL_TAP"TRUE";
"B \NAC \NWC"3;
"S \NAC"
BN"12"120;
%"TAP"
"1","(-1300,2750)","2","standard","I44";
;
CDS_LIB"standard"
BODY_TYPE"PLUMBING"
HDL_TAP"TRUE";
"B \NAC \NWC"4;
"S \NAC"
BN"10"125;
%"TAP"
"1","(-1300,2950)","2","standard","I45";
;
CDS_LIB"standard"
BODY_TYPE"PLUMBING"
HDL_TAP"TRUE";
"B \NAC \NWC"4;
"S \NAC"
BN"11"117;
%"TAP"
"1","(-1300,3150)","2","standard","I46";
;
CDS_LIB"standard"
BODY_TYPE"PLUMBING"
HDL_TAP"TRUE";
"B \NAC \NWC"4;
"S \NAC"
BN"12"118;
%"TAP"
"1","(-1550,3300)","2","standard","I47";
;
CDS_LIB"standard"
BODY_TYPE"PLUMBING"
HDL_TAP"TRUE";
"B \NAC \NWC"3;
"S \NAC"
BN"13"115;
%"TAP"
"1","(-1550,3500)","2","standard","I48";
;
CDS_LIB"standard"
BODY_TYPE"PLUMBING"
HDL_TAP"TRUE";
"B \NAC \NWC"3;
"S \NAC"
BN"14"127;
%"TAP"
"1","(-1550,3700)","2","standard","I49";
;
CDS_LIB"standard"
BODY_TYPE"PLUMBING"
HDL_TAP"TRUE";
"B \NAC \NWC"3;
"S \NAC"
BN"15"122;
%"TAP"
"1","(-1550,325)","2","standard","I5";
;
CDS_LIB"standard"
BODY_TYPE"PLUMBING"
HDL_TAP"TRUE";
"B \NAC \NWC"1;
"S \NAC"
BN"0"144;
%"TAP"
"1","(-1300,3350)","2","standard","I50";
;
CDS_LIB"standard"
BODY_TYPE"PLUMBING"
HDL_TAP"TRUE";
"B \NAC \NWC"4;
"S \NAC"
BN"13"119;
%"TAP"
"1","(-1300,3550)","2","standard","I51";
;
CDS_LIB"standard"
BODY_TYPE"PLUMBING"
HDL_TAP"TRUE";
"B \NAC \NWC"4;
"S \NAC"
BN"14"126;
%"TAP"
"1","(-1300,3750)","2","standard","I52";
;
CDS_LIB"standard"
BODY_TYPE"PLUMBING"
HDL_TAP"TRUE";
"B \NAC \NWC"4;
"S \NAC"
BN"15"121;
%"Q_CAP_DIFFBUS"
"2","(-575,2350)","2","pure_quanta","I53";
;
PART_NUMBER"SP_CH4221MEE01"
VALUE"DIFF BUS_0.22UF"
$LOCATION"C916"
TOLERANCE"20%"
PACK_TYPE"C0201"
MATERIAL"X6S"
VOLTAGE"6.3V"
PIN_NAMES_ROTATE"TRUE"
CDS_LIB"pure_quanta"
CDS_LMAN_SYM_OUTLINE"-25,50,25,-50"
$LOCATION"C916"
CDS_LOCATION"C916"
$SEC"1"
CDS_SEC"1";
"2"
$PN"2"124;
"1"
$PN"1"110;
%"Q_CAP_DIFFBUS"
"2","(-575,2300)","2","pure_quanta","I54";
;
PART_NUMBER"SP_CH4221MEE01"
VALUE"DIFF BUS_0.22UF"
$LOCATION"C917"
TOLERANCE"20%"
PACK_TYPE"C0201"
MATERIAL"X6S"
VOLTAGE"6.3V"
PIN_NAMES_ROTATE"TRUE"
CDS_LIB"pure_quanta"
CDS_LMAN_SYM_OUTLINE"-25,50,25,-50"
$LOCATION"C917"
CDS_LOCATION"C917"
$SEC"1"
CDS_SEC"1";
"2"
$PN"2"17;
"1"
$PN"1"98;
%"Q_CAP_DIFFBUS"
"2","(-575,2500)","2","pure_quanta","I55";
;
PART_NUMBER"SP_CH4221MEE01"
VALUE"DIFF BUS_0.22UF"
$LOCATION"C915"
TOLERANCE"20%"
PACK_TYPE"C0201"
MATERIAL"X6S"
VOLTAGE"6.3V"
PIN_NAMES_ROTATE"TRUE"
CDS_LIB"pure_quanta"
CDS_LMAN_SYM_OUTLINE"-25,50,25,-50"
$LOCATION"C915"
CDS_LOCATION"C915"
$SEC"1"
CDS_SEC"1";
"2"
$PN"2"123;
"1"
$PN"1"109;
%"Q_CAP_DIFFBUS"
"2","(-575,2550)","2","pure_quanta","I56";
;
PART_NUMBER"SP_CH4221MEE01"
VALUE"DIFF BUS_0.22UF"
$LOCATION"C914"
TOLERANCE"20%"
PACK_TYPE"C0201"
MATERIAL"X6S"
VOLTAGE"6.3V"
PIN_NAMES_ROTATE"TRUE"
CDS_LMAN_SYM_OUTLINE"-25,50,25,-50"
CDS_LIB"pure_quanta"
$LOCATION"C914"
CDS_LOCATION"C914"
$SEC"1"
CDS_SEC"1";
"2"
$PN"2"116;
"1"
$PN"1"100;
%"Q_CAP_DIFFBUS"
"2","(-575,2700)","2","pure_quanta","I57";
;
PART_NUMBER"SP_CH4221MEE01"
VALUE"DIFF BUS_0.22UF"
$LOCATION"C913"
TOLERANCE"20%"
PACK_TYPE"C0201"
MATERIAL"X6S"
VOLTAGE"6.3V"
PIN_NAMES_ROTATE"TRUE"
CDS_LIB"pure_quanta"
CDS_LMAN_SYM_OUTLINE"-25,50,25,-50"
$LOCATION"C913"
CDS_LOCATION"C913"
$SEC"1"
CDS_SEC"1";
"2"
$PN"2"114;
"1"
$PN"1"82;
%"Q_CAP_DIFFBUS"
"2","(-575,2750)","2","pure_quanta","I58";
;
PART_NUMBER"SP_CH4221MEE01"
VALUE"DIFF BUS_0.22UF"
$LOCATION"C912"
TOLERANCE"20%"
PACK_TYPE"C0201"
MATERIAL"X6S"
VOLTAGE"6.3V"
PIN_NAMES_ROTATE"TRUE"
CDS_LIB"pure_quanta"
CDS_LMAN_SYM_OUTLINE"-25,50,25,-50"
$LOCATION"C912"
CDS_LOCATION"C912"
$SEC"1"
CDS_SEC"1";
"2"
$PN"2"125;
"1"
$PN"1"83;
%"Q_CAP_DIFFBUS"
"2","(-575,2900)","2","pure_quanta","I59";
;
PART_NUMBER"SP_CH4221MEE01"
VALUE"DIFF BUS_0.22UF"
$LOCATION"C911"
TOLERANCE"20%"
PACK_TYPE"C0201"
MATERIAL"X6S"
VOLTAGE"6.3V"
PIN_NAMES_ROTATE"TRUE"
CDS_LMAN_SYM_OUTLINE"-25,50,25,-50"
CDS_LIB"pure_quanta"
$LOCATION"C911"
CDS_LOCATION"C911"
$SEC"1"
CDS_SEC"1";
"2"
$PN"2"128;
"1"
$PN"1"113;
%"TAP"
"1","(-1550,525)","2","standard","I6";
;
CDS_LIB"standard"
BODY_TYPE"PLUMBING"
HDL_TAP"TRUE";
"B \NAC \NWC"1;
"S \NAC"
BN"1"142;
%"Q_CAP_DIFFBUS"
"2","(-575,2950)","2","pure_quanta","I60";
;
PART_NUMBER"SP_CH4221MEE01"
VALUE"DIFF BUS_0.22UF"
$LOCATION"C910"
TOLERANCE"20%"
PACK_TYPE"C0201"
MATERIAL"X6S"
VOLTAGE"6.3V"
PIN_NAMES_ROTATE"TRUE"
CDS_LMAN_SYM_OUTLINE"-25,50,25,-50"
CDS_LIB"pure_quanta"
$LOCATION"C910"
CDS_LOCATION"C910"
$SEC"1"
CDS_SEC"1";
"2"
$PN"2"117;
"1"
$PN"1"104;
%"Q_CAP_DIFFBUS"
"2","(-575,3100)","2","pure_quanta","I61";
;
PART_NUMBER"SP_CH4221MEE01"
VALUE"DIFF BUS_0.22UF"
$LOCATION"C909"
TOLERANCE"20%"
PACK_TYPE"C0201"
MATERIAL"X6S"
VOLTAGE"6.3V"
PIN_NAMES_ROTATE"TRUE"
CDS_LIB"pure_quanta"
CDS_LMAN_SYM_OUTLINE"-25,50,25,-50"
$LOCATION"C909"
CDS_LOCATION"C909"
$SEC"1"
CDS_SEC"1";
"2"
$PN"2"120;
"1"
$PN"1"101;
%"Q_CAP_DIFFBUS"
"2","(-575,3150)","2","pure_quanta","I62";
;
PART_NUMBER"SP_CH4221MEE01"
VALUE"DIFF BUS_0.22UF"
$LOCATION"C908"
TOLERANCE"20%"
PACK_TYPE"C0201"
MATERIAL"X6S"
VOLTAGE"6.3V"
PIN_NAMES_ROTATE"TRUE"
CDS_LIB"pure_quanta"
CDS_LMAN_SYM_OUTLINE"-25,50,25,-50"
$LOCATION"C908"
CDS_LOCATION"C908"
$SEC"1"
CDS_SEC"1";
"2"
$PN"2"118;
"1"
$PN"1"102;
%"Q_CAP_DIFFBUS"
"2","(-575,3350)","2","pure_quanta","I63";
;
PART_NUMBER"SP_CH4221MEE01"
VALUE"DIFF BUS_0.22UF"
$LOCATION"C906"
TOLERANCE"20%"
PACK_TYPE"C0201"
MATERIAL"X6S"
VOLTAGE"6.3V"
PIN_NAMES_ROTATE"TRUE"
CDS_LIB"pure_quanta"
CDS_LMAN_SYM_OUTLINE"-25,50,25,-50"
$LOCATION"C906"
CDS_LOCATION"C906"
$SEC"1"
CDS_SEC"1";
"2"
$PN"2"119;
"1"
$PN"1"108;
%"Q_CAP_DIFFBUS"
"2","(-575,3300)","2","pure_quanta","I64";
;
PART_NUMBER"SP_CH4221MEE01"
VALUE"DIFF BUS_0.22UF"
$LOCATION"C907"
TOLERANCE"20%"
PACK_TYPE"C0201"
MATERIAL"X6S"
VOLTAGE"6.3V"
PIN_NAMES_ROTATE"TRUE"
CDS_LIB"pure_quanta"
CDS_LMAN_SYM_OUTLINE"-25,50,25,-50"
$LOCATION"C907"
CDS_LOCATION"C907"
$SEC"1"
CDS_SEC"1";
"2"
$PN"2"115;
"1"
$PN"1"103;
%"Q_CAP_DIFFBUS"
"2","(-575,3500)","2","pure_quanta","I65";
;
PART_NUMBER"SP_CH4221MEE01"
VALUE"DIFF BUS_0.22UF"
$LOCATION"C905"
TOLERANCE"20%"
PACK_TYPE"C0201"
MATERIAL"X6S"
VOLTAGE"6.3V"
PIN_NAMES_ROTATE"TRUE"
CDS_LIB"pure_quanta"
CDS_LMAN_SYM_OUTLINE"-25,50,25,-50"
$LOCATION"C905"
CDS_LOCATION"C905"
$SEC"1"
CDS_SEC"1";
"2"
$PN"2"127;
"1"
$PN"1"107;
%"Q_CAP_DIFFBUS"
"2","(-575,3550)","2","pure_quanta","I66";
;
PART_NUMBER"SP_CH4221MEE01"
VALUE"DIFF BUS_0.22UF"
$LOCATION"C904"
TOLERANCE"20%"
PACK_TYPE"C0201"
MATERIAL"X6S"
VOLTAGE"6.3V"
PIN_NAMES_ROTATE"TRUE"
CDS_LIB"pure_quanta"
CDS_LMAN_SYM_OUTLINE"-25,50,25,-50"
$LOCATION"C904"
CDS_LOCATION"C904"
$SEC"1"
CDS_SEC"1";
"2"
$PN"2"126;
"1"
$PN"1"99;
%"Q_CAP_DIFFBUS"
"2","(-575,3700)","2","pure_quanta","I67";
;
PART_NUMBER"SP_CH4221MEE01"
VALUE"DIFF BUS_0.22UF"
$LOCATION"C903"
TOLERANCE"20%"
PACK_TYPE"C0201"
MATERIAL"X6S"
VOLTAGE"6.3V"
PIN_NAMES_ROTATE"TRUE"
CDS_LIB"pure_quanta"
CDS_LMAN_SYM_OUTLINE"-25,50,25,-50"
$LOCATION"C903"
CDS_LOCATION"C903"
$SEC"1"
CDS_SEC"1";
"2"
$PN"2"122;
"1"
$PN"1"106;
%"Q_CAP_DIFFBUS"
"2","(-575,3750)","2","pure_quanta","I68";
;
PART_NUMBER"SP_CH4221MEE01"
PACK_TYPE"C0201"
VALUE"DIFF BUS_0.22UF"
VOLTAGE"6.3V"
TOLERANCE"20%"
MATERIAL"X6S"
$LOCATION"C902"
PIN_NAMES_ROTATE"TRUE"
CDS_LMAN_SYM_OUTLINE"-25,50,25,-50"
CDS_LIB"pure_quanta"
$LOCATION"C902"
CDS_LOCATION"C902"
$SEC"1"
CDS_SEC"1";
"2"
$PN"2"121;
"1"
$PN"1"105;
%"TAP"
"1","(-25,3550)","0","standard","I69";
;
CDS_LIB"standard"
BODY_TYPE"PLUMBING"
HDL_TAP"TRUE";
"B \NAC \NWC"8;
"S \NAC"
BN"14"99;
%"TAP"
"1","(-1300,375)","2","standard","I7";
;
CDS_LIB"standard"
BODY_TYPE"PLUMBING"
HDL_TAP"TRUE";
"B \NAC \NWC"2;
"S \NAC"
BN"0"135;
%"TAP"
"1","(-25,2950)","0","standard","I70";
;
CDS_LIB"standard"
BODY_TYPE"PLUMBING"
HDL_TAP"TRUE";
"B \NAC \NWC"8;
"S \NAC"
BN"11"104;
%"TAP"
"1","(-25,3350)","0","standard","I71";
;
CDS_LIB"standard"
BODY_TYPE"PLUMBING"
HDL_TAP"TRUE";
"B \NAC \NWC"8;
"S \NAC"
BN"13"108;
%"TAP"
"1","(-25,3150)","0","standard","I72";
;
CDS_LIB"standard"
BODY_TYPE"PLUMBING"
HDL_TAP"TRUE";
"B \NAC \NWC"8;
"S \NAC"
BN"12"102;
%"TAP"
"1","(-25,2750)","0","standard","I73";
;
CDS_LIB"standard"
BODY_TYPE"PLUMBING"
HDL_TAP"TRUE";
"B \NAC \NWC"8;
"S \NAC"
BN"10"83;
%"TAP"
"1","(-25,2350)","0","standard","I74";
;
CDS_LIB"standard"
BODY_TYPE"PLUMBING"
HDL_TAP"TRUE";
"B \NAC \NWC"8;
"S \NAC"
BN"8"110;
%"TAP"
"1","(-25,2550)","0","standard","I75";
;
CDS_LIB"standard"
BODY_TYPE"PLUMBING"
HDL_TAP"TRUE";
"B \NAC \NWC"8;
"S \NAC"
BN"9"100;
%"TAP"
"1","(-25,1775)","0","standard","I76";
;
CDS_LIB"standard"
BODY_TYPE"PLUMBING"
HDL_TAP"TRUE";
"B \NAC \NWC"7;
"S \NAC"
BN"7"111;
%"TAP"
"1","(-25,1375)","0","standard","I77";
;
CDS_LIB"standard"
BODY_TYPE"PLUMBING"
HDL_TAP"TRUE";
"B \NAC \NWC"7;
"S \NAC"
BN"5"95;
%"TAP"
"1","(-25,1575)","0","standard","I78";
;
CDS_LIB"standard"
BODY_TYPE"PLUMBING"
HDL_TAP"TRUE";
"B \NAC \NWC"7;
"S \NAC"
BN"6"97;
%"TAP"
"1","(-25,975)","0","standard","I79";
;
CDS_LIB"standard"
BODY_TYPE"PLUMBING"
HDL_TAP"TRUE";
"B \NAC \NWC"7;
"S \NAC"
BN"3"87;
%"TAP"
"1","(-1300,575)","2","standard","I8";
;
CDS_LIB"standard"
BODY_TYPE"PLUMBING"
HDL_TAP"TRUE";
"B \NAC \NWC"2;
"S \NAC"
BN"1"141;
%"TAP"
"1","(-25,1175)","0","standard","I80";
;
CDS_LIB"standard"
BODY_TYPE"PLUMBING"
HDL_TAP"TRUE";
"B \NAC \NWC"7;
"S \NAC"
BN"4"90;
%"TAP"
"1","(-25,775)","0","standard","I81";
;
CDS_LIB"standard"
BODY_TYPE"PLUMBING"
HDL_TAP"TRUE";
"B \NAC \NWC"7;
"S \NAC"
BN"2"93;
%"TAP"
"1","(-25,575)","0","standard","I82";
;
CDS_LIB"standard"
BODY_TYPE"PLUMBING"
HDL_TAP"TRUE";
"B \NAC \NWC"7;
"S \NAC"
BN"1"91;
%"TAP"
"1","(-25,375)","0","standard","I83";
;
CDS_LIB"standard"
BODY_TYPE"PLUMBING"
HDL_TAP"TRUE";
"B \NAC \NWC"7;
"S \NAC"
BN"0"89;
%"TAP"
"1","(-25,3750)","0","standard","I84";
;
CDS_LIB"standard"
BODY_TYPE"PLUMBING"
HDL_TAP"TRUE";
"B \NAC \NWC"8;
"S \NAC"
BN"15"105;
%"TAP"
"1","(175,325)","0","standard","I85";
;
CDS_LIB"standard"
BODY_TYPE"PLUMBING"
HDL_TAP"TRUE";
"B \NAC \NWC"6;
"S \NAC"
BN"0"88;
%"TAP"
"1","(175,525)","0","standard","I86";
;
CDS_LIB"standard"
BODY_TYPE"PLUMBING"
HDL_TAP"TRUE";
"B \NAC \NWC"6;
"S \NAC"
BN"1"92;
%"TAP"
"1","(175,725)","0","standard","I87";
;
CDS_LIB"standard"
BODY_TYPE"PLUMBING"
HDL_TAP"TRUE";
"B \NAC \NWC"6;
"S \NAC"
BN"2"86;
%"TAP"
"1","(175,925)","0","standard","I88";
;
CDS_LIB"standard"
BODY_TYPE"PLUMBING"
HDL_TAP"TRUE";
"B \NAC \NWC"6;
"S \NAC"
BN"3"84;
%"TAP"
"1","(175,1125)","0","standard","I89";
;
CDS_LIB"standard"
BODY_TYPE"PLUMBING"
HDL_TAP"TRUE";
"B \NAC \NWC"6;
"S \NAC"
BN"4"85;
%"TAP"
"1","(-1550,725)","2","standard","I9";
;
CDS_LIB"standard"
BODY_TYPE"PLUMBING"
HDL_TAP"TRUE";
"B \NAC \NWC"1;
"S \NAC"
BN"2"131;
%"TAP"
"1","(175,1325)","0","standard","I90";
;
CDS_LIB"standard"
BODY_TYPE"PLUMBING"
HDL_TAP"TRUE";
"B \NAC \NWC"6;
"S \NAC"
BN"5"94;
%"TAP"
"1","(175,1525)","0","standard","I91";
;
CDS_LIB"standard"
BODY_TYPE"PLUMBING"
HDL_TAP"TRUE";
"B \NAC \NWC"6;
"S \NAC"
BN"6"96;
%"TAP"
"1","(175,1725)","0","standard","I92";
;
CDS_LIB"standard"
BODY_TYPE"PLUMBING"
HDL_TAP"TRUE";
"B \NAC \NWC"6;
"S \NAC"
BN"7"112;
%"TAP"
"1","(175,2300)","0","standard","I97";
;
CDS_LIB"standard"
BODY_TYPE"PLUMBING"
HDL_TAP"TRUE";
"B \NAC \NWC"5;
"S \NAC"
BN"8"98;
%"TAP"
"1","(175,2500)","0","standard","I98";
;
CDS_LIB"standard"
BODY_TYPE"PLUMBING"
HDL_TAP"TRUE";
"B \NAC \NWC"5;
"S \NAC"
BN"9"109;
%"TAP"
"1","(175,2900)","0","standard","I99";
;
CDS_LIB"standard"
BODY_TYPE"PLUMBING"
HDL_TAP"TRUE";
"B \NAC \NWC"5;
"S \NAC"
BN"11"113;
END.
